FILE_TYPE = CONNECTIVITY;
{Allegro Design Entry HDL 17.2-2016 S066 (3851973) 4/6/2020}
"PAGE_NUMBER" = 14;
0"NC";
1"XP3R3V_FPGA\g";
2"XP2R5V_FPGA\g";
3"XP5R0V\g";
4"SG\g";
5"XP3R3V_PCIE\g";
6"XP3R3V_AUX_PCIE\g";
7"XP3R3V_FPGA\g";
8"SG\g";
9"XP12R0V\g";
10"SG\g";
11"XP3R3V_FT4232\g";
12"SG\g";
13"SG\g";
14"XP3R3V_FPGA\g";
15"SG\g";
16"XP3R3V_FPGA\g";
17"SMA2_LED_GREEN_N";
18"SMA4_LED_GREEN_N";
19"GPS_SMA_LED_BLUE_N";
20"GPS_SMA_LED_RED_N";
21"RGB_LED_SHUTDOWN_N";
22"SMA2_LED_RED_N";
23"R_RGB_LED_I2C_SDA";
24"R_RGB_LED_I2C_SCL";
25"SMA1_LED_GREEN_N";
26"SMA1_LED_BLUE_N";
27"SMA2_LED_BLUE_N";
28"SMA3_LED_GREEN_N";
29"SMA3_LED_BLUE_N";
30"SMA3_LED_RED_N";
31"FPGA_M_RGB_LED_I2C_SDA";
32"FPGA_M_RGB_LED_I2C_SCL";
33"RGB_LED_I2C_SDA";
34"RGB_LED_I2C_SCL";
35"SMA1_LED_RED_N";
36"LED_DATOUT1";
37"LED_DATOUT0";
38"FPGA_OUT_RGB_LED_SHUTDOWN_N";
39"UN$14$IS32FL3207QWLA3TRQFN29$I219$ISET";
40"SMA4_LED_GREEN_N";
41"GPS_SMA_LED_BLUE_N";
42"GPS_SMA_LED_GREEN_N";
43"FPGA_OUT_SMA3_LED_RED_N";
44"FPGA_OUT_SMA4_LED_RED_N";
45"FPGA_OUT_SMA4_LED_BLUE_N";
46"SMA2_LED_GREEN_N";
47"FPGA_OUT_SMA2_LED_GREEN_N";
48"FPGA_OUT_GPS_LED_GREEN_N";
49"FPGA_OUT_SMA4_LED_GREEN_N";
50"UN$14$IS32FL3207QWLA3TRQFN29$I219$AD";
51"SMA4_LED_RED_N";
52"SMA3_LED_BLUE_N";
53"FPGA_OUT_SMA1_LED_BLUE_N";
54"SMA1_LED_GREEN_N";
55"FPGA_OUT_GPS_LED_RED_N";
56"SMA3_LED_GREEN_N";
57"SMA2_LED_BLUE_N";
58"SMA1_LED_BLUE_N";
59"FPGA_OUT_SMA1_LED_RED_N";
60"FPGA_OUT_SMA1_LED_GREEN_N";
61"GPS_SMA_LED_RED_N";
62"UN$14$LED4PV14$I265$1";
63"UN$14$LED4PV14$I267$3";
64"UN$14$LED4PV14$I267$4";
65"UN$14$LED4PV14$I267$1";
66"UN$14$LED4PV14$I268$3";
67"UN$14$LED4PV14$I268$4";
68"UN$14$LED4PV14$I268$1";
69"UN$14$LED4PV14$I269$4";
70"UN$14$LED4PV14$I269$1";
71"FPGA_OUT_GPS_LED_BLUE_N";
72"GPS_SMA_LED_GREEN_N";
73"UN$14$LED4PV14$I269$3";
74"UN$14$LED4PV14$I265$3";
75"UN$14$LED4PV14$I265$4";
76"SMA4_LED_BLUE_N";
77"SMA3_LED_RED_N";
78"UN$14$LED4PV14$I266$4";
79"SMA1_LED_RED_N";
80"UN$14$LED4PV14$I266$3";
81"FPGA_OUT_SMA2_LED_BLUE_N";
82"SMA4_LED_BLUE_N";
83"SMA4_LED_RED_N";
84"FPGA_OUT_SMA3_LED_BLUE_N";
85"FPGA_OUT_SMA3_LED_GREEN_N";
86"UN$14$LED4PV14$I266$1";
87"SMA2_LED_RED_N";
88"UN$14$RESISTOR$I58$2";
89"UN$14$OPTICAL$I141$A";
90"LED_DATOUT3";
91"UN$14$OPTICAL$I292$A";
92"UN$14$OPTICAL$I140$A";
93"UN$14$OPTICAL$I143$A";
94"UN$14$OPTICAL$I194$A";
95"UN$14$OPTICAL$I289$A";
96"FPGA_OUT_SMA2_LED_RED_N";
97"UN$14$OPTICAL$I137$A";
98"UN$14$OPTICAL$I191$A";
99"UN$14$RESISTOR$I65$2";
100"UN$14$OPTICAL$I142$A";
101"UN$14$OPTICAL$I139$A";
102"FPGA_USR_LED0";
103"FPGA_USR_LED1";
104"LED_DATOUT2";
105"FPGA_DONE";
106"UN$14$OPTICAL$I138$A";
107"UN$14$OPTICAL$I136$A";
108"UN$14$OPTICAL$I11$A";
109"UN$14$OPTICAL$I12$A";
%"RESISTOR"
"1","(-2800,10750)","0","passive","I107";
;
$LOCATION"R385"
CDS_LOCATION"R385"
$SEC"1"
CDS_SEC"1"
PACKAGE"0402"
VALUE"33OHM"
TOLERANCE"1%"
CDS_LIB"passive"
CDS_LMAN_SYM_OUTLINE"-50,50,100,-50"
CLS_PN"G155-133R0-01";
"1"
$PN"1"58;
"2"
$PN"2"62;
%"RESISTOR"
"1","(-2800,11350)","0","passive","I108";
;
$LOCATION"R386"
CDS_LOCATION"R386"
$SEC"1"
CDS_SEC"1"
PACKAGE"0402"
VALUE"33OHM"
CLS_PN"G155-133R0-01"
CDS_LMAN_SYM_OUTLINE"-50,50,100,-50"
CDS_LIB"passive"
TOLERANCE"1%";
"1"
$PN"1"54;
"2"
$PN"2"75;
%"OPTICAL"
"1","(-10500,12050)","2","discrete","I11";
;
$LOCATION"DS2"
CDS_LOCATION"DS2"
$SEC"1"
CDS_SEC"1"
CLS_PN"G170-10143-01"
PART_NUMBER"LTST-C190KGKT"
CDS_LMAN_SYM_OUTLINE"-150,100,150,-50"
CDS_LIB"discrete";
"C"
$PN"C"104;
"A"
$PN"A"108;
%"RESISTOR"
"1","(-2800,11050)","0","passive","I110";
;
$LOCATION"R387"
CDS_LOCATION"R387"
$SEC"1"
CDS_SEC"1"
PACKAGE"0402"
VALUE"33OHM"
TOLERANCE"1%"
CDS_LMAN_SYM_OUTLINE"-50,50,100,-50"
CDS_LIB"passive"
CLS_PN"G155-133R0-01";
"1"
$PN"1"79;
"2"
$PN"2"74;
%"OPTICAL"
"1","(-10500,12400)","2","discrete","I12";
;
$LOCATION"DS1"
CDS_LOCATION"DS1"
$SEC"1"
CDS_SEC"1"
CLS_PN"G170-10143-01"
PART_NUMBER"LTST-C190KGKT"
CDS_LIB"discrete"
CDS_LMAN_SYM_OUTLINE"-150,100,150,-50";
"C"
$PN"C"90;
"A"
$PN"A"109;
%"VCC"
"1","(-500,12050)","0","cls","I128";
;
VOLTAGE"3.3V"
HDL_POWER"XP3R3V_FPGA"
CDS_LMAN_SYM_OUTLINE"-250,250,250,-250"
CDS_LIB"cls"
BODY_TYPE"PLUMBING";
"$PIN0"16;
%"OPTICAL"
"1","(-10500,11700)","2","discrete","I136";
;
LOCATION"DS3"
$SEC"1"
CDS_SEC"1"
CLS_PN"G170-10143-01"
PART_NUMBER"LTST-C190KGKT"
CDS_LMAN_SYM_OUTLINE"-150,100,150,-50"
CDS_LIB"discrete";
"C"
$PN"C"36;
"A"
$PN"A"107;
%"OPTICAL"
"1","(-10500,11350)","2","discrete","I137";
;
LOCATION"DS4"
$SEC"1"
CDS_SEC"1"
PART_NUMBER"LTST-C190KGKT"
CLS_PN"G170-10143-01"
CDS_LMAN_SYM_OUTLINE"-150,100,150,-50"
CDS_LIB"discrete";
"C"
$PN"C"37;
"A"
$PN"A"97;
%"OPTICAL"
"1","(-10500,10950)","2","discrete","I138";
;
LOCATION"DS10"
$SEC"1"
CDS_SEC"1"
PART_NUMBER"LTST-C190KGKT"
CLS_PN"G170-10143-01"
CDS_LIB"discrete"
CDS_LMAN_SYM_OUTLINE"-150,100,150,-50";
"C"
$PN"C"103;
"A"
$PN"A"106;
%"OPTICAL"
"1","(-10500,10650)","2","discrete","I139";
;
LOCATION"DS11"
$SEC"1"
CDS_SEC"1"
PART_NUMBER"LTST-C190KGKT"
CLS_PN"G170-10143-01"
CDS_LIB"discrete"
CDS_LMAN_SYM_OUTLINE"-150,100,150,-50";
"C"
$PN"C"102;
"A"
$PN"A"101;
%"OPTICAL"
"1","(-10600,9200)","2","discrete","I140";
;
LOCATION"DS6"
$SEC"1"
CDS_SEC"1"
PART_NUMBER"LTST-C190KGKT"
CLS_PN"G170-10143-01"
CDS_LIB"discrete"
CDS_LMAN_SYM_OUTLINE"-150,100,150,-50";
"C"
$PN"C"8;
"A"
$PN"A"92;
%"OPTICAL"
"1","(-10600,8850)","2","discrete","I141";
;
LOCATION"DS7"
$SEC"1"
CDS_SEC"1"
CLS_PN"G170-10143-01"
PART_NUMBER"LTST-C190KGKT"
CDS_LIB"discrete"
CDS_LMAN_SYM_OUTLINE"-150,100,150,-50";
"C"
$PN"C"8;
"A"
$PN"A"89;
%"OPTICAL"
"1","(-10600,8500)","2","discrete","I142";
;
LOCATION"DS8"
$SEC"1"
CDS_SEC"1"
PART_NUMBER"LTST-C190KGKT"
CLS_PN"G170-10143-01"
CDS_LIB"discrete"
CDS_LMAN_SYM_OUTLINE"-150,100,150,-50";
"C"
$PN"C"8;
"A"
$PN"A"100;
%"OPTICAL"
"1","(-10600,8100)","2","discrete","I143";
;
LOCATION"DS5"
$SEC"1"
CDS_SEC"1"
PART_NUMBER"LTST-C190KGKT"
CLS_PN"G170-10143-01"
CDS_LIB"discrete"
CDS_LMAN_SYM_OUTLINE"-150,100,150,-50";
"C"
$PN"C"8;
"A"
$PN"A"93;
%"RESISTOR"
"1","(-2800,9550)","0","passive","I146";
;
LOCATION"R390"
$SEC"1"
CDS_SEC"1"
PACKAGE"0402"
VALUE"33OHM"
TOLERANCE"1%"
CDS_LMAN_SYM_OUTLINE"-50,50,100,-50"
CDS_LIB"passive"
CLS_PN"G155-133R0-01";
"1"
$PN"1"87;
"2"
$PN"2"80;
%"RESISTOR"
"1","(-2800,9250)","0","passive","I147";
;
LOCATION"R388"
$SEC"1"
CDS_SEC"1"
VALUE"33OHM"
PACKAGE"0402"
CLS_PN"G155-133R0-01"
CDS_LIB"passive"
CDS_LMAN_SYM_OUTLINE"-50,50,100,-50"
TOLERANCE"1%";
"1"
$PN"1"57;
"2"
$PN"2"86;
%"RESISTOR"
"1","(-2800,9850)","0","passive","I148";
;
LOCATION"R389"
$SEC"1"
CDS_SEC"1"
VALUE"33OHM"
PACKAGE"0402"
CDS_LIB"passive"
CDS_LMAN_SYM_OUTLINE"-50,50,100,-50"
CLS_PN"G155-133R0-01"
TOLERANCE"1%";
"1"
$PN"1"46;
"2"
$PN"2"78;
%"RESISTOR"
"1","(-2800,8300)","0","passive","I149";
;
LOCATION"R392"
$SEC"1"
CDS_SEC"1"
PACKAGE"0402"
VALUE"33OHM"
CDS_LMAN_SYM_OUTLINE"-50,50,100,-50"
CDS_LIB"passive"
CLS_PN"G155-133R0-01"
TOLERANCE"1%";
"1"
$PN"1"56;
"2"
$PN"2"64;
%"RESISTOR"
"1","(-2800,7700)","0","passive","I150";
;
LOCATION"R391"
$SEC"1"
CDS_SEC"1"
PACKAGE"0402"
VALUE"33OHM"
CLS_PN"G155-133R0-01"
CDS_LMAN_SYM_OUTLINE"-50,50,100,-50"
CDS_LIB"passive"
TOLERANCE"1%";
"1"
$PN"1"52;
"2"
$PN"2"65;
%"RESISTOR"
"1","(-2800,8000)","0","passive","I151";
;
LOCATION"R393"
$SEC"1"
CDS_SEC"1"
PACKAGE"0402"
VALUE"33OHM"
TOLERANCE"1%"
CDS_LIB"passive"
CDS_LMAN_SYM_OUTLINE"-50,50,100,-50"
CLS_PN"G155-133R0-01";
"1"
$PN"1"77;
"2"
$PN"2"63;
%"RESISTOR"
"1","(-2800,6750)","0","passive","I152";
;
LOCATION"R395"
$SEC"1"
CDS_SEC"1"
PACKAGE"0402"
VALUE"33OHM"
CDS_LMAN_SYM_OUTLINE"-50,50,100,-50"
CDS_LIB"passive"
CLS_PN"G155-133R0-01"
TOLERANCE"1%";
"1"
$PN"1"40;
"2"
$PN"2"67;
%"RESISTOR"
"1","(-2800,6150)","0","passive","I153";
;
LOCATION"R394"
$SEC"1"
CDS_SEC"1"
PACKAGE"0402"
VALUE"33OHM"
CLS_PN"G155-133R0-01"
CDS_LMAN_SYM_OUTLINE"-50,50,100,-50"
CDS_LIB"passive"
TOLERANCE"1%";
"1"
$PN"1"76;
"2"
$PN"2"68;
%"RESISTOR"
"1","(-2800,6450)","0","passive","I154";
;
LOCATION"R396"
$SEC"1"
CDS_SEC"1"
PACKAGE"0402"
VALUE"33OHM"
TOLERANCE"1%"
CDS_LIB"passive"
CDS_LMAN_SYM_OUTLINE"-50,50,100,-50"
CLS_PN"G155-133R0-01";
"1"
$PN"1"51;
"2"
$PN"2"66;
%"RESISTOR"
"1","(-2750,5200)","0","passive","I155";
;
LOCATION"R398"
$SEC"1"
CDS_SEC"1"
PACKAGE"0402"
VALUE"33OHM"
CDS_LIB"passive"
CDS_LMAN_SYM_OUTLINE"-50,50,100,-50"
CLS_PN"G155-133R0-01"
TOLERANCE"1%";
"1"
$PN"1"72;
"2"
$PN"2"69;
%"RESISTOR"
"1","(-2750,4600)","0","passive","I156";
;
LOCATION"R397"
$SEC"1"
CDS_SEC"1"
VALUE"33OHM"
PACKAGE"0402"
CLS_PN"G155-133R0-01"
CDS_LIB"passive"
CDS_LMAN_SYM_OUTLINE"-50,50,100,-50"
TOLERANCE"1%";
"1"
$PN"1"41;
"2"
$PN"2"70;
%"RESISTOR"
"1","(-2750,4900)","0","passive","I157";
;
LOCATION"R399"
$SEC"1"
CDS_SEC"1"
VALUE"33OHM"
PACKAGE"0402"
TOLERANCE"1%"
CDS_LMAN_SYM_OUTLINE"-50,50,100,-50"
CDS_LIB"passive"
CLS_PN"G155-133R0-01";
"1"
$PN"1"61;
"2"
$PN"2"73;
%"RESISTOR"
"1","(-2800,10600)","0","passive","I160";
;
$LOCATION"R124"
CDS_LOCATION"R124"
$SEC"1"
CDS_SEC"1"
NO_ASSY"TRUE"
PACKAGE"0402"
VALUE"100OHM"
TOLERANCE"1%"
CLS_PN"G155-11000-01"
CDS_LIB"passive"
CDS_LMAN_SYM_OUTLINE"-50,50,100,-50";
"1"
$PN"1"53;
"2"
$PN"2"62;
%"RESISTOR"
"1","(-2800,11200)","0","passive","I161";
;
$LOCATION"R125"
CDS_LOCATION"R125"
$SEC"1"
CDS_SEC"1"
NO_ASSY"TRUE"
PACKAGE"0402"
VALUE"100OHM"
TOLERANCE"1%"
CDS_LMAN_SYM_OUTLINE"-50,50,100,-50"
CDS_LIB"passive"
CLS_PN"G155-11000-01";
"1"
$PN"1"60;
"2"
$PN"2"75;
%"RESISTOR"
"1","(-2800,10900)","0","passive","I163";
;
$LOCATION"R272"
CDS_LOCATION"R272"
$SEC"1"
CDS_SEC"1"
PACKAGE"0402"
NO_ASSY"TRUE"
VALUE"100OHM"
TOLERANCE"1%"
CDS_LIB"passive"
CDS_LMAN_SYM_OUTLINE"-50,50,100,-50"
CLS_PN"G155-11000-01";
"1"
$PN"1"59;
"2"
$PN"2"74;
%"RESISTOR"
"1","(-2800,9100)","0","passive","I165";
;
$LOCATION"R273"
CDS_LOCATION"R273"
$SEC"1"
CDS_SEC"1"
NO_ASSY"TRUE"
PACKAGE"0402"
VALUE"100OHM"
CDS_LMAN_SYM_OUTLINE"-50,50,100,-50"
CDS_LIB"passive"
CLS_PN"G155-11000-01"
TOLERANCE"1%";
"1"
$PN"1"81;
"2"
$PN"2"86;
%"RESISTOR"
"1","(-2800,7550)","0","passive","I168";
;
$LOCATION"R374"
CDS_LOCATION"R374"
$SEC"1"
CDS_SEC"1"
NO_ASSY"TRUE"
PACKAGE"0402"
VALUE"100OHM"
CDS_LIB"passive"
CDS_LMAN_SYM_OUTLINE"-50,50,100,-50"
CLS_PN"G155-11000-01"
TOLERANCE"1%";
"1"
$PN"1"84;
"2"
$PN"2"65;
%"RESISTOR"
"1","(-2750,4450)","0","passive","I170";
;
$LOCATION"R425"
CDS_LOCATION"R425"
$SEC"1"
CDS_SEC"1"
NO_ASSY"TRUE"
VALUE"100OHM"
PACKAGE"0402"
CDS_LMAN_SYM_OUTLINE"-50,50,100,-50"
CDS_LIB"passive"
CLS_PN"G155-11000-01"
TOLERANCE"1%";
"1"
$PN"1"71;
"2"
$PN"2"70;
%"RESISTOR"
"1","(-2800,9700)","0","passive","I171";
;
$LOCATION"R274"
CDS_LOCATION"R274"
$SEC"1"
CDS_SEC"1"
NO_ASSY"TRUE"
PACKAGE"0402"
VALUE"100OHM"
TOLERANCE"1%"
CDS_LMAN_SYM_OUTLINE"-50,50,100,-50"
CDS_LIB"passive"
CLS_PN"G155-11000-01";
"1"
$PN"1"47;
"2"
$PN"2"78;
%"RESISTOR"
"1","(-2800,8150)","0","passive","I174";
;
$LOCATION"R375"
CDS_LOCATION"R375"
$SEC"1"
CDS_SEC"1"
NO_ASSY"TRUE"
PACKAGE"0402"
VALUE"100OHM"
TOLERANCE"1%"
CDS_LIB"passive"
CDS_LMAN_SYM_OUTLINE"-50,50,100,-50"
CLS_PN"G155-11000-01";
"1"
$PN"1"85;
"2"
$PN"2"64;
%"RESISTOR"
"1","(-2800,6600)","0","passive","I176";
;
$LOCATION"R401"
CDS_LOCATION"R401"
$SEC"1"
CDS_SEC"1"
NO_ASSY"TRUE"
PACKAGE"0402"
VALUE"100OHM"
TOLERANCE"1%"
CDS_LIB"passive"
CDS_LMAN_SYM_OUTLINE"-50,50,100,-50"
CLS_PN"G155-11000-01";
"1"
$PN"1"49;
"2"
$PN"2"67;
%"RESISTOR"
"1","(-2800,6000)","0","passive","I177";
;
$LOCATION"R400"
CDS_LOCATION"R400"
$SEC"1"
CDS_SEC"1"
NO_ASSY"TRUE"
PACKAGE"0402"
VALUE"100OHM"
CDS_LMAN_SYM_OUTLINE"-50,50,100,-50"
CDS_LIB"passive"
CLS_PN"G155-11000-01"
TOLERANCE"1%";
"1"
$PN"1"45;
"2"
$PN"2"68;
%"RESISTOR"
"1","(-2750,5050)","0","passive","I179";
;
$LOCATION"R426"
CDS_LOCATION"R426"
$SEC"1"
CDS_SEC"1"
NO_ASSY"TRUE"
PACKAGE"0402"
VALUE"100OHM"
TOLERANCE"1%"
CDS_LMAN_SYM_OUTLINE"-50,50,100,-50"
CDS_LIB"passive"
CLS_PN"G155-11000-01";
"1"
$PN"1"48;
"2"
$PN"2"69;
%"RESISTOR"
"1","(-2800,9400)","0","passive","I181";
;
$LOCATION"R373"
CDS_LOCATION"R373"
$SEC"1"
CDS_SEC"1"
PACKAGE"0402"
NO_ASSY"TRUE"
VALUE"100OHM"
TOLERANCE"1%"
CDS_LIB"passive"
CDS_LMAN_SYM_OUTLINE"-50,50,100,-50"
CLS_PN"G155-11000-01";
"1"
$PN"1"96;
"2"
$PN"2"80;
%"RESISTOR"
"1","(-2800,7850)","0","passive","I184";
;
$LOCATION"R376"
CDS_LOCATION"R376"
$SEC"1"
CDS_SEC"1"
NO_ASSY"TRUE"
PACKAGE"0402"
VALUE"100OHM"
TOLERANCE"1%"
CDS_LMAN_SYM_OUTLINE"-50,50,100,-50"
CDS_LIB"passive"
CLS_PN"G155-11000-01";
"1"
$PN"1"43;
"2"
$PN"2"63;
%"RESISTOR"
"1","(-2800,6300)","0","passive","I186";
;
$LOCATION"R424"
CDS_LOCATION"R424"
$SEC"1"
CDS_SEC"1"
NO_ASSY"TRUE"
PACKAGE"0402"
VALUE"100OHM"
TOLERANCE"1%"
CDS_LMAN_SYM_OUTLINE"-50,50,100,-50"
CDS_LIB"passive"
CLS_PN"G155-11000-01";
"1"
$PN"1"44;
"2"
$PN"2"66;
%"RESISTOR"
"1","(-2750,4750)","0","passive","I188";
;
$LOCATION"R427"
CDS_LOCATION"R427"
$SEC"1"
CDS_SEC"1"
NO_ASSY"TRUE"
PACKAGE"0402"
VALUE"100OHM"
TOLERANCE"1%"
CDS_LIB"passive"
CDS_LMAN_SYM_OUTLINE"-50,50,100,-50"
CLS_PN"G155-11000-01";
"1"
$PN"1"55;
"2"
$PN"2"73;
%"RESISTOR"
"1","(-9250,7750)","0","passive","I190";
;
$LOCATION"R118"
CDS_LOCATION"R118"
$SEC"1"
CDS_SEC"1"
VALUE"330OHM"
PACKAGE"0402"
TOLERANCE"1%"
CLS_PN"G155-13300-01"
CDS_LMAN_SYM_OUTLINE"-50,50,100,-50"
CDS_LIB"passive";
"1"
$PN"1"98;
"2"
$PN"2"5;
%"OPTICAL"
"1","(-10600,7750)","2","discrete","I191";
;
$LOCATION"DS19"
CDS_LOCATION"DS19"
$SEC"1"
CDS_SEC"1"
CLS_PN"G170-10143-01"
PART_NUMBER"LTST-C190KGKT"
CDS_LMAN_SYM_OUTLINE"-150,100,150,-50"
CDS_LIB"discrete";
"C"
$PN"C"8;
"A"
$PN"A"98;
%"RESISTOR"
"1","(-9250,7400)","0","passive","I192";
;
$LOCATION"R119"
CDS_LOCATION"R119"
$SEC"1"
CDS_SEC"1"
VALUE"330OHM"
PACKAGE"0402"
TOLERANCE"1%"
CDS_LIB"passive"
CDS_LMAN_SYM_OUTLINE"-50,50,100,-50"
CLS_PN"G155-13300-01";
"1"
$PN"1"94;
"2"
$PN"2"6;
%"OPTICAL"
"1","(-10600,7400)","2","discrete","I194";
;
$LOCATION"DS20"
CDS_LOCATION"DS20"
$SEC"1"
CDS_SEC"1"
CLS_PN"G170-10143-01"
PART_NUMBER"LTST-C190KGKT"
CDS_LIB"discrete"
CDS_LMAN_SYM_OUTLINE"-150,100,150,-50";
"C"
$PN"C"8;
"A"
$PN"A"94;
%"VCC"
"1","(-7850,7500)","0","cls","I195";
;
HDL_POWER"XP3R3V_AUX_PCIE"
VOLTAGE"3.3"
BODY_TYPE"PLUMBING"
CDS_LIB"cls"
CDS_LMAN_SYM_OUTLINE"-250,250,250,-250";
"$PIN0"6;
%"VCC"
"1","(-7850,7850)","0","cls","I196";
;
HDL_POWER"XP3R3V_PCIE"
VOLTAGE"3.3"
BODY_TYPE"PLUMBING"
CDS_LIB"cls"
CDS_LMAN_SYM_OUTLINE"-250,250,250,-250";
"$PIN0"5;
%"IS32FL3207_QWLA3_TR_QFN29"
"1","(-9200,5700)","0","interface","I219";
;
$LOCATION"U33"
CDS_LOCATION"U33"
$SEC"1"
CDS_SEC"1"
CLS_PN"A223-00002-FB"
VALUE"IS32FL3207-QWLA3-TR"
CDS_LMAN_SYM_OUTLINE"0,0,750,-2600"
CDS_LIB"interface";
"THRM_PAD"
$PN"29"15;
"OUT18"
$PN"28"0;
"OUT17"
$PN"27"0;
"OUT16"
$PN"26"0;
"GND_4"
$PN"25"15;
"OUT15"
$PN"24"19;
"OUT14"
$PN"23"20;
"OUT13"
$PN"22"42;
"OUT12"
$PN"21"82;
"OUT11"
$PN"20"83;
"OUT10"
$PN"19"18;
"GND_3"
$PN"18"15;
"OUT9"
$PN"17"29;
"OUT8"
$PN"16"30;
"OUT7"
$PN"15"28;
"OUT6"
$PN"14"27;
"OUT5"
$PN"13"22;
"OUT4"
$PN"12"17;
"GND_2"
$PN"11"15;
"OUT3"
$PN"10"26;
"OUT2"
$PN"9"35;
"OUT1"
$PN"8"25;
"SCL"
$PN"7"24;
"SDA"
$PN"6"23;
"ISET"
$PN"5"39;
"GND_1"
$PN"4"15;
"VCC"
$PN"3"14;
"AD"
$PN"2"50;
"SDB* \B"
$PN"1"21;
%"GND_SG"
"1","(-8200,3050)","0","cls","I235";
;
HDL_POWER"SG"
CDS_LMAN_SYM_OUTLINE"0,0,100,-50"
CDS_LIB"cls"
BODY_TYPE"PLUMBING";
"SGND"15;
%"VCC"
"1","(-11750,6300)","0","cls","I236";
;
VOLTAGE"3.3V"
HDL_POWER"XP3R3V_FPGA"
CDS_LIB"cls"
CDS_LMAN_SYM_OUTLINE"-250,250,250,-250"
BODY_TYPE"PLUMBING";
"$PIN0"14;
%"CAPACITOR"
"2","(-10150,5900)","2","passive","I237";
;
$LOCATION"C315"
CDS_LOCATION"C315"
$SEC"1"
CDS_SEC"1"
VALUE"0.1UF"
VOLTAGE"25V"
PACKAGE"0402"
CLS_PN"G105-0B104-EK"
TOLERANCE"10%"
CDS_LMAN_SYM_OUTLINE"-50,0,50,-50"
CDS_LIB"passive";
"2"
$PN"2"13;
"1"
$PN"1"14;
%"CAPACITOR"
"2","(-10550,5900)","2","passive","I238";
;
$LOCATION"C314"
CDS_LOCATION"C314"
$SEC"1"
CDS_SEC"1"
VALUE"10UF"
PACKAGE"0402"
VOLTAGE"6.3V"
CLS_PN"G105-0C106-BM"
TOLERANCE"20%"
CDS_LMAN_SYM_OUTLINE"-50,0,50,-50"
CDS_LIB"passive";
"2"
$PN"2"13;
"1"
$PN"1"14;
%"GND_SG"
"1","(-10200,5550)","0","cls","I239";
;
HDL_POWER"SG"
CDS_LMAN_SYM_OUTLINE"0,0,100,-50"
CDS_LIB"cls"
BODY_TYPE"PLUMBING";
"SGND"13;
%"RESISTOR"
"2","(-10050,3750)","0","passive","I246";
;
$LOCATION"R323"
CDS_LOCATION"R323"
$SEC"1"
CDS_SEC"1"
VALUE"4.7KOHM"
PACKAGE"0402"
CDS_LIB"passive"
CDS_LMAN_SYM_OUTLINE"-50,50,50,-100"
CLS_PN"G155-14701-01"
TOLERANCE"1%";
"1"
$PN"1"39;
"2"
$PN"2"12;
%"RESISTOR"
"1","(-9600,3700)","1","passive","I247";
;
$LOCATION"R324"
CDS_LOCATION"R324"
$SEC"1"
CDS_SEC"1"
PACKAGE"0402"
VALUE"0OHM"
CLS_PN"G155-100R0-J0"
CDS_LMAN_SYM_OUTLINE"-50,50,100,-50"
CDS_LIB"passive"
TOLERANCE"-";
"1"
$PN"1"12;
"2"
$PN"2"50;
%"GND_SG"
"1","(-10100,3350)","0","cls","I248";
;
HDL_POWER"SG"
CDS_LMAN_SYM_OUTLINE"0,0,100,-50"
CDS_LIB"cls"
BODY_TYPE"PLUMBING";
"SGND"12;
%"RESISTOR"
"1","(-11900,4800)","0","passive","I249";
;
$LOCATION"R319"
CDS_LOCATION"R319"
$SEC"1"
CDS_SEC"1"
PACKAGE"0402"
VALUE"33OHM"
NO_ASSY"TRUE"
TOLERANCE"1%"
CLS_PN"G155-133R0-01"
SIGNAL_MODEL"DEFAULT_RESISTOR_33OHM_2_1"
CDS_LMAN_SYM_OUTLINE"-50,50,100,-50"
CDS_LIB"passive";
"1"
$PN"1"38;
"2"
$PN"2"21;
%"CAPACITOR"
"2","(-9750,4600)","2","passive","I250";
;
$LOCATION"C316"
CDS_LOCATION"C316"
$SEC"1"
CDS_SEC"1"
VALUE"0.1UF"
PACKAGE"0402"
VOLTAGE"25V"
TOLERANCE"10%"
CLS_PN"G105-0B104-EK"
CDS_LMAN_SYM_OUTLINE"-50,0,50,-50"
CDS_LIB"passive";
"2"
$PN"2"4;
"1"
$PN"1"21;
%"GND_SG"
"1","(-9800,4350)","0","cls","I252";
;
HDL_POWER"SG"
BODY_TYPE"PLUMBING"
CDS_LMAN_SYM_OUTLINE"0,0,100,-50"
CDS_LIB"cls";
"SGND"4;
%"RESISTOR"
"1","(-11900,5200)","0","passive","I257";
;
$LOCATION"R322"
CDS_LOCATION"R322"
$SEC"1"
CDS_SEC"1"
NO_ASSY"TRUE"
PACKAGE"0402"
VALUE"33OHM"
TOLERANCE"1%"
CLS_PN"G155-133R0-01"
CDS_LIB"passive"
CDS_LMAN_SYM_OUTLINE"-50,50,100,-50"
SIGNAL_MODEL"DEFAULT_RESISTOR_33OHM_2_1";
"1"
$PN"1"32;
"2"
$PN"2"24;
%"RESISTOR"
"1","(-11900,5300)","0","passive","I258";
;
$LOCATION"R321"
CDS_LOCATION"R321"
$SEC"1"
CDS_SEC"1"
VALUE"33OHM"
NO_ASSY"TRUE"
PACKAGE"0402"
TOLERANCE"1%"
CLS_PN"G155-133R0-01"
SIGNAL_MODEL"DEFAULT_RESISTOR_33OHM_2_1"
CDS_LMAN_SYM_OUTLINE"-50,50,100,-50"
CDS_LIB"passive";
"1"
$PN"1"31;
"2"
$PN"2"23;
%"RESISTOR"
"2","(-11400,5850)","0","passive","I259";
;
$LOCATION"R317"
CDS_LOCATION"R317"
$SEC"1"
CDS_SEC"1"
PACKAGE"0402"
VALUE"10KOHM"
TOLERANCE"1%"
CDS_LIB"passive"
CDS_LMAN_SYM_OUTLINE"-50,50,50,-100"
CLS_PN"G155-11002-01";
"1"
$PN"1"14;
"2"
$PN"2"23;
%"RESISTOR"
"2","(-11000,5850)","0","passive","I261";
;
$LOCATION"R318"
CDS_LOCATION"R318"
$SEC"1"
CDS_SEC"1"
PACKAGE"0402"
VALUE"10KOHM"
TOLERANCE"1%"
CDS_LIB"passive"
CDS_LMAN_SYM_OUTLINE"-50,50,50,-100"
CLS_PN"G155-11002-01";
"1"
$PN"1"14;
"2"
$PN"2"24;
%"RESISTOR"
"2","(-9700,5500)","0","passive","I264";
;
LOCATION"R320"
$SEC"1"
CDS_SEC"1"
PACKAGE"0402"
VALUE"4.7KOHM"
TOLERANCE"1%"
CDS_LIB"passive"
CDS_LMAN_SYM_OUTLINE"-50,50,50,-100"
CLS_PN"G155-14701-01";
"1"
$PN"1"14;
"2"
$PN"2"21;
%"LED_4P_V14"
"1","(-1200,11650)","2","discrete","I265";
;
LOCATION"DS14"
$SEC"1"
CDS_SEC"1"
PART_NUMBER"APFA2507QBDSEEZGKC"
CLS_PN"G170-10189-01"
CDS_LMAN_SYM_OUTLINE"0,0,700,-1150"
CDS_LIB"discrete";
"2"
$PN"2"16;
"1"
$PN"1"62;
"3"
$PN"3"74;
"4"
$PN"4"75;
%"LED_4P_V14"
"1","(-1200,10150)","2","discrete","I266";
;
LOCATION"DS15"
$SEC"1"
CDS_SEC"1"
CLS_PN"G170-10189-01"
PART_NUMBER"APFA2507QBDSEEZGKC"
CDS_LIB"discrete"
CDS_LMAN_SYM_OUTLINE"0,0,700,-1150";
"2"
$PN"2"16;
"1"
$PN"1"86;
"3"
$PN"3"80;
"4"
$PN"4"78;
%"LED_4P_V14"
"1","(-1200,8600)","2","discrete","I267";
;
LOCATION"DS16"
$SEC"1"
CDS_SEC"1"
CLS_PN"G170-10189-01"
PART_NUMBER"APFA2507QBDSEEZGKC"
CDS_LIB"discrete"
CDS_LMAN_SYM_OUTLINE"0,0,700,-1150";
"2"
$PN"2"16;
"1"
$PN"1"65;
"3"
$PN"3"63;
"4"
$PN"4"64;
%"LED_4P_V14"
"1","(-1200,7050)","2","discrete","I268";
;
LOCATION"DS17"
$SEC"1"
CDS_SEC"1"
CLS_PN"G170-10189-01"
PART_NUMBER"APFA2507QBDSEEZGKC"
CDS_LMAN_SYM_OUTLINE"0,0,700,-1150"
CDS_LIB"discrete";
"2"
$PN"2"16;
"1"
$PN"1"68;
"3"
$PN"3"66;
"4"
$PN"4"67;
%"LED_4P_V14"
"1","(-1200,5500)","2","discrete","I269";
;
LOCATION"DS18"
$SEC"1"
CDS_SEC"1"
CLS_PN"G170-10189-01"
PART_NUMBER"APFA2507QBDSEEZGKC"
CDS_LIB"discrete"
CDS_LMAN_SYM_OUTLINE"0,0,700,-1150";
"2"
$PN"2"16;
"1"
$PN"1"70;
"3"
$PN"3"73;
"4"
$PN"4"69;
%"RESISTOR"
"1","(-9250,7050)","0","passive","I288";
;
$LOCATION"R169"
CDS_LOCATION"R169"
$SEC"1"
CDS_SEC"1"
VALUE"330OHM"
PACKAGE"0402"
CDS_LIB"passive"
CDS_LMAN_SYM_OUTLINE"-50,50,100,-50"
TOLERANCE"1%"
CLS_PN"G155-13300-01";
"1"
$PN"1"95;
"2"
$PN"2"11;
%"OPTICAL"
"1","(-10600,7050)","2","discrete","I289";
;
$LOCATION"DS12"
CDS_LOCATION"DS12"
$SEC"1"
CDS_SEC"1"
PART_NUMBER"LTST-C190KGKT"
CLS_PN"G170-10143-01"
CDS_LIB"discrete"
CDS_LMAN_SYM_OUTLINE"-150,100,150,-50";
"C"
$PN"C"8;
"A"
$PN"A"95;
%"VCC"
"1","(-7850,7150)","0","cls","I290";
;
VOLTAGE"3.3V"
HDL_POWER"XP3R3V_FT4232"
CDS_LIB"cls"
CDS_LMAN_SYM_OUTLINE"-250,250,250,-250"
BODY_TYPE"PLUMBING";
"$PIN0"11;
%"OPTICAL"
"1","(-11250,10200)","2","discrete","I292";
;
LOCATION"DS9"
$SEC"1"
CDS_SEC"1"
CLS_PN"G170-10143-01"
PART_NUMBER"LTST-C190KGKT"
CDS_LIB"discrete"
CDS_LMAN_SYM_OUTLINE"-150,100,150,-50";
"C"
$PN"C"10;
"A"
$PN"A"91;
%"RESISTOR"
"1","(-10150,10200)","0","passive","I293";
;
$LOCATION"R208"
CDS_LOCATION"R208"
$SEC"1"
CDS_SEC"1"
VALUE"330OHM"
TOLERANCE"1%"
CDS_LIB"passive"
CDS_LMAN_SYM_OUTLINE"-50,50,100,-50"
CLS_PN"G155-13300-01";
"1"
$PN"1"91;
"2"
$PN"2"105;
%"GND_SG"
"1","(-12850,10050)","0","cls","I294";
;
HDL_POWER"SG"
CDS_LIB"cls"
CDS_LMAN_SYM_OUTLINE"0,0,100,-50"
BODY_TYPE"PLUMBING";
"SGND"10;
%"RESISTOR"
"1","(-11900,5100)","0","passive","I298";
;
$LOCATION"R364"
CDS_LOCATION"R364"
$SEC"1"
CDS_SEC"1"
PACKAGE"0402"
VALUE"33OHM"
TOLERANCE"1%"
CLS_PN"G155-133R0-01"
SIGNAL_MODEL"DEFAULT_RESISTOR_33OHM_2_1"
CDS_LMAN_SYM_OUTLINE"-50,50,100,-50"
CDS_LIB"passive";
"1"
$PN"1"33;
"2"
$PN"2"23;
%"RESISTOR"
"1","(-11900,5000)","0","passive","I299";
;
$LOCATION"R366"
CDS_LOCATION"R366"
$SEC"1"
CDS_SEC"1"
PACKAGE"0402"
VALUE"33OHM"
CDS_LIB"passive"
CDS_LMAN_SYM_OUTLINE"-50,50,100,-50"
SIGNAL_MODEL"DEFAULT_RESISTOR_33OHM_2_1"
CLS_PN"G155-133R0-01"
TOLERANCE"1%";
"1"
$PN"1"34;
"2"
$PN"2"24;
%"VCC"
"1","(-7850,8600)","0","cls","I39";
;
HDL_POWER"XP5R0V"
VOLTAGE"5.0V"
BODY_TYPE"PLUMBING"
CDS_LMAN_SYM_OUTLINE"-250,250,250,-250"
CDS_LIB"cls";
"$PIN0"3;
%"RESISTOR"
"1","(-9150,8500)","0","passive","I44";
;
$LOCATION"R180"
CDS_LOCATION"R180"
$SEC"1"
CDS_SEC"1"
PACKAGE"0402"
VALUE"1KOHM"
TOLERANCE"1%"
CDS_LIB"passive"
CDS_LMAN_SYM_OUTLINE"-50,50,100,-50"
CLS_PN"G155-11001-01";
"1"
$PN"1"100;
"2"
$PN"2"3;
%"VCC"
"1","(-7850,8200)","0","cls","I50";
;
HDL_POWER"XP12R0V"
VOLTAGE"12V"
CDS_LIB"cls"
CDS_LMAN_SYM_OUTLINE"-250,250,250,-250"
BODY_TYPE"PLUMBING";
"$PIN0"9;
%"GND_SG"
"1","(-12300,6900)","0","cls","I51";
;
HDL_POWER"SG"
CDS_LMAN_SYM_OUTLINE"0,0,100,-50"
CDS_LIB"cls"
BODY_TYPE"PLUMBING";
"SGND"8;
%"VCC"
"1","(-7750,12550)","0","cls","I57";
;
VOLTAGE"3.3V"
HDL_POWER"XP3R3V_FPGA"
BODY_TYPE"PLUMBING"
CDS_LMAN_SYM_OUTLINE"-250,250,250,-250"
CDS_LIB"cls";
"$PIN0"7;
%"RESISTOR"
"1","(-9600,8850)","0","passive","I58";
;
$LOCATION"R108"
CDS_LOCATION"R108"
$SEC"1"
CDS_SEC"1"
VALUE"100OHM"
PACKAGE"0402"
TOLERANCE"1%"
CDS_LIB"passive"
CDS_LMAN_SYM_OUTLINE"-50,50,100,-50"
CLS_PN"G155-11000-01";
"1"
$PN"1"89;
"2"
$PN"2"88;
%"VCC"
"1","(-7850,8950)","0","cls","I59";
;
VOLTAGE"2.5V"
HDL_POWER"XP2R5V_FPGA"
CDS_LMAN_SYM_OUTLINE"-250,250,250,-250"
CDS_LIB"cls"
BODY_TYPE"PLUMBING";
"$PIN0"2;
%"RESISTOR"
"1","(-8650,8850)","0","passive","I60";
;
$LOCATION"R139"
CDS_LOCATION"R139"
$SEC"1"
CDS_SEC"1"
VALUE"33OHM"
PACKAGE"0402"
TOLERANCE"1%"
CLS_PN"G155-133R0-01"
CDS_LMAN_SYM_OUTLINE"-50,50,100,-50"
CDS_LIB"passive";
"1"
$PN"1"88;
"2"
$PN"2"2;
%"VCC"
"1","(-7850,9300)","0","cls","I62";
;
HDL_POWER"XP3R3V_FPGA"
VOLTAGE"3.3V"
BODY_TYPE"PLUMBING"
CDS_LIB"cls"
CDS_LMAN_SYM_OUTLINE"-250,250,250,-250";
"$PIN0"1;
%"RESISTOR"
"1","(-9250,9200)","0","passive","I63";
;
$LOCATION"R138"
CDS_LOCATION"R138"
$SEC"1"
CDS_SEC"1"
PACKAGE"0402"
VALUE"330OHM"
TOLERANCE"1%"
CLS_PN"G155-13300-01"
CDS_LIB"passive"
CDS_LMAN_SYM_OUTLINE"-50,50,100,-50";
"1"
$PN"1"92;
"2"
$PN"2"1;
%"RESISTOR"
"1","(-9650,8100)","0","passive","I65";
;
$LOCATION"R256"
CDS_LOCATION"R256"
$SEC"1"
CDS_SEC"1"
VALUE"1KOHM"
PACKAGE"0402"
TOLERANCE"1%"
CLS_PN"G155-11001-01"
CDS_LMAN_SYM_OUTLINE"-50,50,100,-50"
CDS_LIB"passive";
"1"
$PN"1"93;
"2"
$PN"2"99;
%"RESISTOR"
"1","(-8750,8100)","0","passive","I66";
;
$LOCATION"R262"
CDS_LOCATION"R262"
$SEC"1"
CDS_SEC"1"
PACKAGE"0402"
VALUE"1KOHM"
TOLERANCE"1%"
CDS_LIB"passive"
CDS_LMAN_SYM_OUTLINE"-50,50,100,-50"
CLS_PN"G155-11001-01";
"1"
$PN"1"99;
"2"
$PN"2"9;
%"RESISTOR"
"1","(-8900,12400)","0","passive","I67";
;
$LOCATION"R257"
CDS_LOCATION"R257"
$SEC"1"
CDS_SEC"1"
VALUE"330OHM"
PACKAGE"0402"
CLS_PN"G155-13300-01"
CDS_LMAN_SYM_OUTLINE"-50,50,100,-50"
CDS_LIB"passive"
TOLERANCE"1%";
"1"
$PN"1"109;
"2"
$PN"2"7;
%"RESISTOR"
"1","(-8900,12050)","0","passive","I68";
;
$LOCATION"R258"
CDS_LOCATION"R258"
$SEC"1"
CDS_SEC"1"
VALUE"330OHM"
PACKAGE"0402"
CLS_PN"G155-13300-01"
CDS_LMAN_SYM_OUTLINE"-50,50,100,-50"
CDS_LIB"passive"
TOLERANCE"1%";
"1"
$PN"1"108;
"2"
$PN"2"7;
%"RESISTOR"
"1","(-8900,11700)","0","passive","I69";
;
$LOCATION"R259"
CDS_LOCATION"R259"
$SEC"1"
CDS_SEC"1"
VALUE"330OHM"
PACKAGE"0402"
CLS_PN"G155-13300-01"
CDS_LMAN_SYM_OUTLINE"-50,50,100,-50"
CDS_LIB"passive"
TOLERANCE"1%";
"1"
$PN"1"107;
"2"
$PN"2"7;
%"RESISTOR"
"1","(-8900,11350)","0","passive","I70";
;
$LOCATION"R261"
CDS_LOCATION"R261"
$SEC"1"
CDS_SEC"1"
PACKAGE"0402"
VALUE"330OHM"
CLS_PN"G155-13300-01"
CDS_LIB"passive"
CDS_LMAN_SYM_OUTLINE"-50,50,100,-50"
TOLERANCE"1%";
"1"
$PN"1"97;
"2"
$PN"2"7;
%"RESISTOR"
"1","(-8900,10950)","0","passive","I72";
;
$LOCATION"R279"
CDS_LOCATION"R279"
$SEC"1"
CDS_SEC"1"
VALUE"330OHM"
PACKAGE"0402"
TOLERANCE"1%"
CDS_LIB"passive"
CDS_LMAN_SYM_OUTLINE"-50,50,100,-50"
CLS_PN"G155-13300-01";
"1"
$PN"1"106;
"2"
$PN"2"7;
%"RESISTOR"
"1","(-8900,10650)","0","passive","I74";
;
$LOCATION"R280"
CDS_LOCATION"R280"
$SEC"1"
CDS_SEC"1"
VALUE"330OHM"
PACKAGE"0402"
TOLERANCE"1%"
CLS_PN"G155-13300-01"
CDS_LMAN_SYM_OUTLINE"-50,50,100,-50"
CDS_LIB"passive";
"1"
$PN"1"101;
"2"
$PN"2"7;
END.
